# T6G (Grand Teton) — schematic netlist excerpt (pin names and nets, part order shuffled) for the footprints in the layout excerpt that follows; sources: Cadence DE-HDL packaged netlist, KiCad conversion of 04192023_DAF0TMB3IC0_F0TG_MB_C_brd_V02_OCP.brd

R645  Q_RES  33 5% CHIP  pkg 0402LF  page 361 : A = PWRGD_P1V8_RETIMER_CPU1 ; B = FM_PWRGD_P1V8_RETIMER_CPU1
C318  Q_CAP  22UF 4V 20% X6S  pkg C0402  page 334 : A = P0V9_CPU1_RT1_2A ; B = GND

(kicad_pcb
	(version 20260206)
	(generator "pcbnew")
	(generator_version "10.0")
	(general
		(thickness 1.6)
		(legacy_teardrops no)
	)
	(paper "A4")
	(title_block
		(title "04192023_DAF0TMB3IC0_F0TG_MB_C_brd_V02_OCP.brd")
		(comment 1 "Grand Teton / footprints 4954-4955 of 8354")
	)
	(layers
		(0 "F.Cu" signal "TOP")
		(4 "In1.Cu" signal "GND")
		(6 "In2.Cu" signal "IN1")
		(8 "In3.Cu" signal "GND1")
		(10 "In4.Cu" signal "IN2")
		(12 "In5.Cu" signal "GND2")
		(14 "In6.Cu" signal "IN3")
		(16 "In7.Cu" signal "GND3")
		(18 "In8.Cu" signal "VCC")
		(20 "In9.Cu" signal "VCC1")
		(22 "In10.Cu" signal "GND4")
		(24 "In11.Cu" signal "IN4")
		(26 "In12.Cu" signal "GND5")
		(28 "In13.Cu" signal "IN5")
		(30 "In14.Cu" signal "GND6")
		(32 "In15.Cu" signal "IN6")
		(34 "In16.Cu" signal "GND7")
		(2 "B.Cu" signal "BOTTOM")
		(9 "F.Adhes" user "F.Adhesive")
		(11 "B.Adhes" user "B.Adhesive")
		(13 "F.Paste" user "Package Geometry/Pastemask Top")
		(15 "B.Paste" user "Package Geometry/Pastemask Bottom")
		(5 "F.SilkS" user "Ref Des/Silkscreen Top")
		(7 "B.SilkS" user "Ref Des/Silkscreen Bottom")
		(1 "F.Mask" user "Board Geometry/Soldermask Top")
		(3 "B.Mask" user "Board Geometry/Soldermask Bottom")
		(17 "Dwgs.User" user "User.Drawings")
		(19 "Cmts.User" user "User.Comments")
		(21 "Eco1.User" user "User.Eco1")
		(23 "Eco2.User" user "User.Eco2")
		(25 "Edge.Cuts" user "Board Geometry/Outline")
		(27 "Margin" user)
		(31 "F.CrtYd" user "Package Geometry/Place Bound Top")
		(29 "B.CrtYd" user "Package Geometry/Place Bound Bottom")
		(35 "F.Fab" user "Ref Des/Assembly Top")
		(33 "B.Fab" user "Ref Des/Assembly Bottom")
	)
	(footprint ""
		(layer "B.Cu")
		(at 84.71916 -390.560052 90)
		(property "Reference" "C318"
			(at 0 0 90)
			(layer "B.SilkS")
			(hide yes)
			(effects
				(font
					(size 1.27 1.27)
				)
				(justify mirror)
			)
		)
		(property "Value" ""
			(at 0 0 90)
			(layer "B.Fab")
			(effects
				(font
					(size 1.27 1.27)
				)
				(justify mirror)
			)
		)
		(duplicate_pad_numbers_are_jumpers no)
		(fp_line
			(start 0.7874 -0.4064)
			(end -0.7874 -0.4064)
			(stroke
				(width 0.1524)
				(type default)
			)
			(layer "B.SilkS")
		)
		(fp_line
			(start -0.7874 -0.4064)
			(end -0.7874 0.4064)
			(stroke
				(width 0.1524)
				(type default)
			)
			(layer "B.SilkS")
		)
		(fp_line
			(start 0.7874 0.4064)
			(end 0.7874 -0.4064)
			(stroke
				(width 0.1524)
				(type default)
			)
			(layer "B.SilkS")
		)
		(fp_line
			(start -0.7874 0.4064)
			(end 0.7874 0.4064)
			(stroke
				(width 0.1524)
				(type default)
			)
			(layer "B.SilkS")
		)
		(fp_line
			(start 0.67945 -0.305054)
			(end 0.12065 -0.305054)
			(stroke
				(width 0.1)
				(type default)
			)
			(layer "B.Fab")
		)
		(fp_line
			(start 0.12065 -0.305054)
			(end 0.12065 -0.2794)
			(stroke
				(width 0.1)
				(type default)
			)
			(layer "B.Fab")
		)
		(fp_line
			(start -0.12065 -0.3048)
			(end -0.67945 -0.3048)
			(stroke
				(width 0.1)
				(type default)
			)
			(layer "B.Fab")
		)
		(fp_line
			(start -0.67945 -0.3048)
			(end -0.67945 0.3048)
			(stroke
				(width 0.1)
				(type default)
			)
			(layer "B.Fab")
		)
		(fp_line
			(start 0.12065 -0.2794)
			(end -0.12065 -0.2794)
			(stroke
				(width 0.1)
				(type default)
			)
			(layer "B.Fab")
		)
		(fp_line
			(start -0.12065 -0.2794)
			(end -0.12065 -0.3048)
			(stroke
				(width 0.1)
				(type default)
			)
			(layer "B.Fab")
		)
		(fp_line
			(start 0.12065 0.2794)
			(end 0.12065 0.3048)
			(stroke
				(width 0.1)
				(type default)
			)
			(layer "B.Fab")
		)
		(fp_line
			(start -0.120396 0.2794)
			(end 0.12065 0.2794)
			(stroke
				(width 0.1)
				(type default)
			)
			(layer "B.Fab")
		)
		(fp_line
			(start 0.67945 0.3048)
			(end 0.67945 -0.305054)
			(stroke
				(width 0.1)
				(type default)
			)
			(layer "B.Fab")
		)
		(fp_line
			(start 0.12065 0.3048)
			(end 0.67945 0.3048)
			(stroke
				(width 0.1)
				(type default)
			)
			(layer "B.Fab")
		)
		(fp_line
			(start -0.120396 0.3048)
			(end -0.120396 0.2794)
			(stroke
				(width 0.1)
				(type default)
			)
			(layer "B.Fab")
		)
		(fp_line
			(start -0.67945 0.3048)
			(end -0.120396 0.3048)
			(stroke
				(width 0.1)
				(type default)
			)
			(layer "B.Fab")
		)
		(pad "1" smd circle
			(at 0.40005 0 270)
			(size 0 0)
			(layers "B.Cu" "B.Mask" "B.Paste")
			(net "P0V9_CPU1_RT1_2A")
		)
		(pad "2" smd circle
			(at -0.40005 0 270)
			(size 0 0)
			(layers "B.Cu" "B.Mask" "B.Paste")
			(net "GND")
		)
	)
	(footprint ""
		(layer "B.Cu")
		(at 228.525578 -289.066732 90)
		(property "Reference" "R645"
			(at 0 0 90)
			(layer "B.SilkS")
			(hide yes)
			(effects
				(font
					(size 1.27 1.27)
				)
				(justify mirror)
			)
		)
		(property "Value" ""
			(at 0 0 90)
			(layer "B.Fab")
			(effects
				(font
					(size 1.27 1.27)
				)
				(justify mirror)
			)
		)
		(duplicate_pad_numbers_are_jumpers no)
		(fp_line
			(start 0.7874 -0.4064)
			(end -0.7874 -0.4064)
			(stroke
				(width 0.1524)
				(type default)
			)
			(layer "B.SilkS")
		)
		(fp_line
			(start -0.7874 -0.4064)
			(end -0.7874 0.4064)
			(stroke
				(width 0.1524)
				(type default)
			)
			(layer "B.SilkS")
		)
		(fp_line
			(start 0.7874 0.4064)
			(end 0.7874 -0.4064)
			(stroke
				(width 0.1524)
				(type default)
			)
			(layer "B.SilkS")
		)
		(fp_line
			(start -0.7874 0.4064)
			(end 0.7874 0.4064)
			(stroke
				(width 0.1524)
				(type default)
			)
			(layer "B.SilkS")
		)
		(fp_line
			(start 0.67945 -0.305054)
			(end 0.12065 -0.305054)
			(stroke
				(width 0.1)
				(type default)
			)
			(layer "B.Fab")
		)
		(fp_line
			(start 0.12065 -0.305054)
			(end 0.12065 -0.2794)
			(stroke
				(width 0.1)
				(type default)
			)
			(layer "B.Fab")
		)
		(fp_line
			(start -0.12065 -0.3048)
			(end -0.67945 -0.3048)
			(stroke
				(width 0.1)
				(type default)
			)
			(layer "B.Fab")
		)
		(fp_line
			(start -0.67945 -0.3048)
			(end -0.67945 0.3048)
			(stroke
				(width 0.1)
				(type default)
			)
			(layer "B.Fab")
		)
		(fp_line
			(start 0.12065 -0.2794)
			(end -0.12065 -0.2794)
			(stroke
				(width 0.1)
				(type default)
			)
			(layer "B.Fab")
		)
		(fp_line
			(start -0.12065 -0.2794)
			(end -0.12065 -0.3048)
			(stroke
				(width 0.1)
				(type default)
			)
			(layer "B.Fab")
		)
		(fp_line
			(start 0.12065 0.2794)
			(end 0.12065 0.3048)
			(stroke
				(width 0.1)
				(type default)
			)
			(layer "B.Fab")
		)
		(fp_line
			(start -0.120396 0.2794)
			(end 0.12065 0.2794)
			(stroke
				(width 0.1)
				(type default)
			)
			(layer "B.Fab")
		)
		(fp_line
			(start 0.67945 0.3048)
			(end 0.67945 -0.305054)
			(stroke
				(width 0.1)
				(type default)
			)
			(layer "B.Fab")
		)
		(fp_line
			(start 0.12065 0.3048)
			(end 0.67945 0.3048)
			(stroke
				(width 0.1)
				(type default)
			)
			(layer "B.Fab")
		)
		(fp_line
			(start -0.120396 0.3048)
			(end -0.120396 0.2794)
			(stroke
				(width 0.1)
				(type default)
			)
			(layer "B.Fab")
		)
		(fp_line
			(start -0.67945 0.3048)
			(end -0.120396 0.3048)
			(stroke
				(width 0.1)
				(type default)
			)
			(layer "B.Fab")
		)
		(pad "1" smd circle
			(at 0.40005 0 270)
			(size 0 0)
			(layers "B.Cu" "B.Mask" "B.Paste")
			(net "PWRGD_P1V8_RETIMER_CPU1")
		)
		(pad "2" smd circle
			(at -0.40005 0 270)
			(size 0 0)
			(layers "B.Cu" "B.Mask" "B.Paste")
			(net "FM_PWRGD_P1V8_RETIMER_CPU1")
		)
	)
)
